# BASEBOARD_FAB2 (Tioga Pass) — schematic netlist excerpt (pin names and nets, part order shuffled) for the footprints in the layout excerpt that follows; sources: Cadence DE-HDL packaged netlist, KiCad conversion of Wiwynn_Tioga_Pass_MB.brd

R8E19  RES  4.75K 1% EMPTY  pkg 0402  page 157 : A = P3V3_STBY ; B = FM_BIOS_TOP_SWAP
C8C5  CAP  10UF 6.3V 20% X6S  pkg 0603  page 130 : A = P3V3_STBY ; B = GND
BT8G1  BATTERY  pkg PLCLF  page 196
C1D32  CAP  1.0UF 16V 10% X6S  pkg 0402  page 209 : A = VR_PVCCIN_CPU1_PH5_VCIN ; B = GND

(kicad_pcb
	(version 20260206)
	(generator "pcbnew")
	(generator_version "10.0")
	(general
		(thickness 1.6)
		(legacy_teardrops no)
	)
	(paper "A4")
	(title_block
		(title "Wiwynn_Tioga_Pass_MB.brd")
		(comment 1 "Tioga Pass / footprints 614-617 of 4770")
	)
	(layers
		(0 "F.Cu" signal "TOP")
		(4 "In1.Cu" signal "L2GND")
		(6 "In2.Cu" signal "L3")
		(8 "In3.Cu" signal "L4GND")
		(10 "In4.Cu" signal "L5")
		(12 "In5.Cu" signal "L6GND")
		(14 "In6.Cu" signal "L7VCC")
		(16 "In7.Cu" signal "L8VCC")
		(18 "In8.Cu" signal "L9GND")
		(20 "In9.Cu" signal "L10")
		(22 "In10.Cu" signal "L11GND")
		(24 "In11.Cu" signal "L12")
		(26 "In12.Cu" signal "L13GND")
		(2 "B.Cu" signal "BOTTOM")
		(9 "F.Adhes" user "F.Adhesive")
		(11 "B.Adhes" user "B.Adhesive")
		(13 "F.Paste" user "Package Geometry/Pastemask Top")
		(15 "B.Paste" user "Package Geometry/Pastemask Bottom")
		(5 "F.SilkS" user "Ref Des/Silkscreen Top")
		(7 "B.SilkS" user "Ref Des/Silkscreen Bottom")
		(1 "F.Mask" user "Board Geometry/Soldermask Top")
		(3 "B.Mask" user "Board Geometry/Soldermask Bottom")
		(17 "Dwgs.User" user "User.Drawings")
		(19 "Cmts.User" user "User.Comments")
		(21 "Eco1.User" user "User.Eco1")
		(23 "Eco2.User" user "User.Eco2")
		(25 "Edge.Cuts" user "Board Geometry/Outline")
		(27 "Margin" user)
		(31 "F.CrtYd" user "Package Geometry/Place Bound Top")
		(29 "B.CrtYd" user "Package Geometry/Place Bound Bottom")
		(35 "F.Fab" user "Ref Des/Assembly Top")
		(33 "B.Fab" user "Ref Des/Assembly Bottom")
	)
	(footprint ""
		(layer "F.Cu")
		(at 422.5798 -21.4122 180)
		(property "Reference" "R8E19"
			(at 0 0 180)
			(layer "F.SilkS")
			(hide yes)
			(effects
				(font
					(size 1.27 1.27)
				)
			)
		)
		(property "Value" ""
			(at 0 0 180)
			(layer "F.Fab")
			(effects
				(font
					(size 1.27 1.27)
				)
			)
		)
		(duplicate_pad_numbers_are_jumpers no)
		(fp_poly
			(pts
				(xy -0.2794 -0.1016) (xy 0.2794 -0.1016) (xy 0.2794 0.9906) (xy -0.2794 0.9906)
			)
			(stroke
				(width 0)
				(type default)
			)
			(fill no)
			(layer "F.CrtYd")
		)
		(fp_line
			(start 0.2794 0.9906)
			(end 0.2794 -0.1016)
			(stroke
				(width 0.1)
				(type default)
			)
			(layer "F.Fab")
		)
		(fp_line
			(start 0.2794 -0.1016)
			(end -0.2794 -0.1016)
			(stroke
				(width 0.1)
				(type default)
			)
			(layer "F.Fab")
		)
		(fp_line
			(start -0.2794 0.9906)
			(end 0.2794 0.9906)
			(stroke
				(width 0.1)
				(type default)
			)
			(layer "F.Fab")
		)
		(fp_line
			(start -0.2794 -0.1016)
			(end -0.2794 0.9906)
			(stroke
				(width 0.1)
				(type default)
			)
			(layer "F.Fab")
		)
		(pad "1" smd rect
			(at 0 0 180)
			(size 0.508 0.508)
			(layers "F.Cu" "F.Mask" "F.Paste")
			(net "P3V3_STBY")
		)
		(pad "2" smd rect
			(at 0 0.889 180)
			(size 0.508 0.508)
			(layers "F.Cu" "F.Mask" "F.Paste")
			(net "FM_BIOS_TOP_SWAP")
		)
		(zone
			(layer "F.Cu")
			(hatch none 0.5)
			(connect_pads
				(clearance 0)
			)
			(min_thickness 0.25)
			(keepout
				(tracks not_allowed)
				(vias allowed)
				(pads allowed)
				(copperpour not_allowed)
				(footprints allowed)
			)
			(placement
				(enabled no)
				(sheetname "")
			)
			(fill
				(thermal_gap 0.5)
				(thermal_bridge_width 0.5)
				(island_removal_mode 0)
			)
			(polygon
				(pts
					(xy 422.8338 -22.0472) (xy 422.3258 -22.0472) (xy 422.3258 -21.6662) (xy 422.8338 -21.6662)
				)
			)
		)
		(zone
			(layer "F.Cu")
			(hatch none 0.5)
			(connect_pads
				(clearance 0)
			)
			(min_thickness 0.25)
			(keepout
				(tracks allowed)
				(vias not_allowed)
				(pads allowed)
				(copperpour not_allowed)
				(footprints allowed)
			)
			(placement
				(enabled no)
				(sheetname "")
			)
			(fill
				(thermal_gap 0.5)
				(thermal_bridge_width 0.5)
				(island_removal_mode 0)
			)
			(polygon
				(pts
					(xy 422.8338 -21.6662) (xy 422.3258 -21.6662) (xy 422.3258 -22.0472) (xy 422.8338 -22.0472)
				)
			)
		)
	)
	(footprint ""
		(layer "F.Cu")
		(at 423.421048 3.679952 180)
		(property "Reference" "BT8G1"
			(at 0 0 180)
			(layer "F.SilkS")
			(hide yes)
			(effects
				(font
					(size 1.27 1.27)
				)
			)
		)
		(property "Value" ""
			(at 0 0 180)
			(layer "F.Fab")
			(effects
				(font
					(size 1.27 1.27)
				)
			)
		)
		(duplicate_pad_numbers_are_jumpers no)
	)
	(footprint ""
		(layer "F.Cu")
		(at 406.654 -94.474792 90)
		(property "Reference" "C8C5"
			(at 0 0 90)
			(layer "F.SilkS")
			(hide yes)
			(effects
				(font
					(size 1.27 1.27)
				)
			)
		)
		(property "Value" ""
			(at 0 0 90)
			(layer "F.Fab")
			(effects
				(font
					(size 1.27 1.27)
				)
			)
		)
		(duplicate_pad_numbers_are_jumpers no)
		(fp_poly
			(pts
				(xy -0.4953 -0.2032) (xy 0.4953 -0.2032) (xy 0.4953 1.6002) (xy -0.4953 1.6002)
			)
			(stroke
				(width 0)
				(type default)
			)
			(fill no)
			(layer "F.CrtYd")
		)
		(fp_line
			(start 0.4953 -0.2032)
			(end 0.4953 1.6002)
			(stroke
				(width 0.1)
				(type default)
			)
			(layer "F.Fab")
		)
		(fp_line
			(start -0.4953 -0.2032)
			(end 0.4953 -0.2032)
			(stroke
				(width 0.1)
				(type default)
			)
			(layer "F.Fab")
		)
		(fp_line
			(start 0.4953 1.6002)
			(end -0.4953 1.6002)
			(stroke
				(width 0.1)
				(type default)
			)
			(layer "F.Fab")
		)
		(fp_line
			(start -0.4953 1.6002)
			(end -0.4953 -0.2032)
			(stroke
				(width 0.1)
				(type default)
			)
			(layer "F.Fab")
		)
		(pad "1" smd rect
			(at 0 0 90)
			(size 0.762 0.889)
			(layers "F.Cu" "F.Mask" "F.Paste")
			(net "P3V3_STBY")
		)
		(pad "2" smd rect
			(at 0 1.397 90)
			(size 0.762 0.889)
			(layers "F.Cu" "F.Mask" "F.Paste")
			(net "GND")
		)
		(zone
			(layer "F.Cu")
			(hatch none 0.5)
			(connect_pads
				(clearance 0)
			)
			(min_thickness 0.25)
			(keepout
				(tracks not_allowed)
				(vias allowed)
				(pads allowed)
				(copperpour not_allowed)
				(footprints allowed)
			)
			(placement
				(enabled no)
				(sheetname "")
			)
			(fill
				(thermal_gap 0.5)
				(thermal_bridge_width 0.5)
				(island_removal_mode 0)
			)
			(polygon
				(pts
					(xy 407.0985 -94.093792) (xy 407.0985 -94.855792) (xy 407.6065 -94.855792) (xy 407.6065 -94.093792)
				)
			)
		)
	)
	(footprint ""
		(layer "F.Cu")
		(at 31.754826 -85.4837 -90)
		(property "Reference" "C1D32"
			(at 0 0 270)
			(layer "F.SilkS")
			(hide yes)
			(effects
				(font
					(size 1.27 1.27)
				)
			)
		)
		(property "Value" ""
			(at 0 0 270)
			(layer "F.Fab")
			(effects
				(font
					(size 1.27 1.27)
				)
			)
		)
		(duplicate_pad_numbers_are_jumpers no)
		(fp_rect
			(start 0.3048 0.9906)
			(end -0.3048 -0.1016)
			(stroke
				(width 0)
				(type default)
			)
			(fill no)
			(layer "F.CrtYd")
		)
		(fp_line
			(start -0.3048 0.9906)
			(end 0.3048 0.9906)
			(stroke
				(width 0.1)
				(type default)
			)
			(layer "F.Fab")
		)
		(fp_line
			(start 0.3048 0.9906)
			(end 0.3048 -0.1016)
			(stroke
				(width 0.1)
				(type default)
			)
			(layer "F.Fab")
		)
		(fp_line
			(start -0.3048 -0.1016)
			(end -0.3048 0.9906)
			(stroke
				(width 0.1)
				(type default)
			)
			(layer "F.Fab")
		)
		(fp_line
			(start 0.3048 -0.1016)
			(end -0.3048 -0.1016)
			(stroke
				(width 0.1)
				(type default)
			)
			(layer "F.Fab")
		)
		(pad "1" smd rect
			(at 0 0 270)
			(size 0.508 0.508)
			(layers "F.Cu" "F.Mask" "F.Paste")
			(net "VR_PVCCIN_CPU1_PH5_VCIN")
		)
		(pad "2" smd rect
			(at 0 0.889 270)
			(size 0.508 0.508)
			(layers "F.Cu" "F.Mask" "F.Paste")
			(net "GND")
		)
		(zone
			(layer "F.Cu")
			(hatch none 0.5)
			(connect_pads
				(clearance 0)
			)
			(min_thickness 0.25)
			(keepout
				(tracks allowed)
				(vias not_allowed)
				(pads allowed)
				(copperpour not_allowed)
				(footprints allowed)
			)
			(placement
				(enabled no)
				(sheetname "")
			)
			(fill
				(thermal_gap 0.5)
				(thermal_bridge_width 0.5)
				(island_removal_mode 0)
			)
			(polygon
				(pts
					(xy 31.119826 -85.2297) (xy 31.500826 -85.2297) (xy 31.500826 -85.7377) (xy 31.119826 -85.7377)
				)
			)
		)
		(zone
			(layer "F.Cu")
			(hatch none 0.5)
			(connect_pads
				(clearance 0)
			)
			(min_thickness 0.25)
			(keepout
				(tracks not_allowed)
				(vias allowed)
				(pads allowed)
				(copperpour not_allowed)
				(footprints allowed)
			)
			(placement
				(enabled no)
				(sheetname "")
			)
			(fill
				(thermal_gap 0.5)
				(thermal_bridge_width 0.5)
				(island_removal_mode 0)
			)
			(polygon
				(pts
					(xy 31.119826 -85.2297) (xy 31.500826 -85.2297) (xy 31.500826 -85.7377) (xy 31.119826 -85.7377)
				)
			)
		)
	)
)
